# BASEBOARD_FAB2 (Tioga Pass) — schematic netlist excerpt (pin names and nets, part order shuffled) for the footprints in the layout excerpt that follows; sources: Cadence DE-HDL packaged netlist, KiCad conversion of Wiwynn_Tioga_Pass_MB.brd

L7C2  IND-150NH-56-GP  pkg DISCRET-GA1  page 212 : S = VR_PVCCIO_CPU0_PH1_SW ; F = PVCCIO_CPU0
C5D18  CAP_A  22.0UF 4V 20% X6S  pkg 0603V  page 42 : A = PVCCIN_CPU0 ; B = GND
R4G13  RES  7.87K 1.0% CHIP  pkg 0402  page 233 : A = VR_COMP_RC_PVPP_GHJ ; B = VR_FB_PVPP_GHJ

(kicad_pcb
	(version 20260206)
	(generator "pcbnew")
	(generator_version "10.0")
	(general
		(thickness 1.6)
		(legacy_teardrops no)
	)
	(paper "A4")
	(title_block
		(title "Wiwynn_Tioga_Pass_MB.brd")
		(comment 1 "Tioga Pass / footprints 1457-1459 of 4770")
	)
	(layers
		(0 "F.Cu" signal "TOP")
		(4 "In1.Cu" signal "L2GND")
		(6 "In2.Cu" signal "L3")
		(8 "In3.Cu" signal "L4GND")
		(10 "In4.Cu" signal "L5")
		(12 "In5.Cu" signal "L6GND")
		(14 "In6.Cu" signal "L7VCC")
		(16 "In7.Cu" signal "L8VCC")
		(18 "In8.Cu" signal "L9GND")
		(20 "In9.Cu" signal "L10")
		(22 "In10.Cu" signal "L11GND")
		(24 "In11.Cu" signal "L12")
		(26 "In12.Cu" signal "L13GND")
		(2 "B.Cu" signal "BOTTOM")
		(9 "F.Adhes" user "F.Adhesive")
		(11 "B.Adhes" user "B.Adhesive")
		(13 "F.Paste" user "Package Geometry/Pastemask Top")
		(15 "B.Paste" user "Package Geometry/Pastemask Bottom")
		(5 "F.SilkS" user "Ref Des/Silkscreen Top")
		(7 "B.SilkS" user "Ref Des/Silkscreen Bottom")
		(1 "F.Mask" user "Board Geometry/Soldermask Top")
		(3 "B.Mask" user "Board Geometry/Soldermask Bottom")
		(17 "Dwgs.User" user "User.Drawings")
		(19 "Cmts.User" user "User.Comments")
		(21 "Eco1.User" user "User.Eco1")
		(23 "Eco2.User" user "User.Eco2")
		(25 "Edge.Cuts" user "Board Geometry/Outline")
		(27 "Margin" user)
		(31 "F.CrtYd" user "Package Geometry/Place Bound Top")
		(29 "B.CrtYd" user "Package Geometry/Place Bound Bottom")
		(35 "F.Fab" user "Ref Des/Assembly Top")
		(33 "B.Fab" user "Ref Des/Assembly Bottom")
	)
	(footprint ""
		(layer "F.Cu")
		(at 175.133 -7.8105 180)
		(property "Reference" "R4G13"
			(at 0 0 180)
			(layer "F.SilkS")
			(hide yes)
			(effects
				(font
					(size 1.27 1.27)
				)
			)
		)
		(property "Value" ""
			(at 0 0 180)
			(layer "F.Fab")
			(effects
				(font
					(size 1.27 1.27)
				)
			)
		)
		(duplicate_pad_numbers_are_jumpers no)
		(fp_rect
			(start 0.2794 -0.1016)
			(end -0.2794 0.9906)
			(stroke
				(width 0)
				(type default)
			)
			(fill no)
			(layer "F.CrtYd")
		)
		(fp_line
			(start 0.2794 0.9906)
			(end 0.2794 -0.1016)
			(stroke
				(width 0.1)
				(type default)
			)
			(layer "F.Fab")
		)
		(fp_line
			(start 0.2794 -0.1016)
			(end -0.2794 -0.1016)
			(stroke
				(width 0.1)
				(type default)
			)
			(layer "F.Fab")
		)
		(fp_line
			(start -0.2794 0.9906)
			(end 0.2794 0.9906)
			(stroke
				(width 0.1)
				(type default)
			)
			(layer "F.Fab")
		)
		(fp_line
			(start -0.2794 -0.1016)
			(end -0.2794 0.9906)
			(stroke
				(width 0.1)
				(type default)
			)
			(layer "F.Fab")
		)
		(pad "1" smd rect
			(at 0 0 180)
			(size 0.508 0.508)
			(layers "F.Cu" "F.Mask" "F.Paste")
			(net "VR_COMP_RC_PVPP_GHJ")
		)
		(pad "2" smd rect
			(at 0 0.889 180)
			(size 0.508 0.508)
			(layers "F.Cu" "F.Mask" "F.Paste")
			(net "VR_FB_PVPP_GHJ")
		)
		(zone
			(layer "F.Cu")
			(hatch none 0.5)
			(connect_pads
				(clearance 0)
			)
			(min_thickness 0.25)
			(keepout
				(tracks allowed)
				(vias not_allowed)
				(pads allowed)
				(copperpour not_allowed)
				(footprints allowed)
			)
			(placement
				(enabled no)
				(sheetname "")
			)
			(fill
				(thermal_gap 0.5)
				(thermal_bridge_width 0.5)
				(island_removal_mode 0)
			)
			(polygon
				(pts
					(xy 174.879 -8.0645) (xy 175.387 -8.0645) (xy 175.387 -8.4455) (xy 174.879 -8.4455)
				)
			)
		)
		(zone
			(layer "F.Cu")
			(hatch none 0.5)
			(connect_pads
				(clearance 0)
			)
			(min_thickness 0.25)
			(keepout
				(tracks not_allowed)
				(vias allowed)
				(pads allowed)
				(copperpour not_allowed)
				(footprints allowed)
			)
			(placement
				(enabled no)
				(sheetname "")
			)
			(fill
				(thermal_gap 0.5)
				(thermal_bridge_width 0.5)
				(island_removal_mode 0)
			)
			(polygon
				(pts
					(xy 174.879 -8.0645) (xy 175.387 -8.0645) (xy 175.387 -8.4455) (xy 174.879 -8.4455)
				)
			)
		)
	)
	(footprint ""
		(layer "F.Cu")
		(at 266.9286 -79.6036 180)
		(property "Reference" "C5D18"
			(at 0 0 180)
			(layer "F.SilkS")
			(hide yes)
			(effects
				(font
					(size 1.27 1.27)
				)
			)
		)
		(property "Value" ""
			(at 0 0 180)
			(layer "F.Fab")
			(effects
				(font
					(size 1.27 1.27)
				)
			)
		)
		(duplicate_pad_numbers_are_jumpers no)
		(fp_poly
			(pts
				(xy -0.4953 -0.2032) (xy 0.4953 -0.2032) (xy 0.4953 1.6002) (xy -0.4953 1.6002)
			)
			(stroke
				(width 0)
				(type default)
			)
			(fill no)
			(layer "F.CrtYd")
		)
		(fp_line
			(start 0.4953 1.6002)
			(end -0.4953 1.6002)
			(stroke
				(width 0.1)
				(type default)
			)
			(layer "F.Fab")
		)
		(fp_line
			(start 0.4953 -0.2032)
			(end 0.4953 1.6002)
			(stroke
				(width 0.1)
				(type default)
			)
			(layer "F.Fab")
		)
		(fp_line
			(start -0.4953 1.6002)
			(end -0.4953 -0.2032)
			(stroke
				(width 0.1)
				(type default)
			)
			(layer "F.Fab")
		)
		(fp_line
			(start -0.4953 -0.2032)
			(end 0.4953 -0.2032)
			(stroke
				(width 0.1)
				(type default)
			)
			(layer "F.Fab")
		)
		(pad "1" smd rect
			(at 0 0 180)
			(size 0.762 0.889)
			(layers "F.Cu" "F.Mask" "F.Paste")
			(net "PVCCIN_CPU0")
		)
		(pad "2" smd rect
			(at 0 1.397 180)
			(size 0.762 0.889)
			(layers "F.Cu" "F.Mask" "F.Paste")
			(net "GND")
		)
		(zone
			(layer "F.Cu")
			(hatch none 0.5)
			(connect_pads
				(clearance 0)
			)
			(min_thickness 0.25)
			(keepout
				(tracks not_allowed)
				(vias allowed)
				(pads allowed)
				(copperpour not_allowed)
				(footprints allowed)
			)
			(placement
				(enabled no)
				(sheetname "")
			)
			(fill
				(thermal_gap 0.5)
				(thermal_bridge_width 0.5)
				(island_removal_mode 0)
			)
			(polygon
				(pts
					(xy 267.3096 -80.0481) (xy 266.5476 -80.0481) (xy 266.5476 -80.5561) (xy 267.3096 -80.5561)
				)
			)
		)
	)
	(footprint ""
		(layer "F.Cu")
		(at 341.249 -98.425 180)
		(property "Reference" "L7C2"
			(at 3.378708 -4.251706 180)
			(unlocked yes)
			(layer "F.SilkS")
			(effects
				(font
					(size 0.4064 0.254)
					(thickness 0.1524)
				)
			)
		)
		(property "Value" ""
			(at 0 0 180)
			(layer "F.Fab")
			(effects
				(font
					(size 1.27 1.27)
				)
			)
		)
		(duplicate_pad_numbers_are_jumpers no)
		(fp_line
			(start 8.3693 3.199892)
			(end -1.1303 3.199892)
			(stroke
				(width 0.1524)
				(type default)
			)
			(layer "F.SilkS")
		)
		(fp_line
			(start 8.3693 1.6637)
			(end 8.3693 3.199892)
			(stroke
				(width 0.1524)
				(type default)
			)
			(layer "F.SilkS")
		)
		(fp_line
			(start 8.3693 -3.199892)
			(end 8.3693 -1.6637)
			(stroke
				(width 0.1524)
				(type default)
			)
			(layer "F.SilkS")
		)
		(fp_line
			(start -1.1303 3.199892)
			(end -1.1303 1.6637)
			(stroke
				(width 0.1524)
				(type default)
			)
			(layer "F.SilkS")
		)
		(fp_line
			(start -1.1303 -1.6637)
			(end -1.1303 -3.199892)
			(stroke
				(width 0.1524)
				(type default)
			)
			(layer "F.SilkS")
		)
		(fp_line
			(start -1.1303 -3.199892)
			(end 8.3693 -3.199892)
			(stroke
				(width 0.1524)
				(type default)
			)
			(layer "F.SilkS")
		)
		(fp_rect
			(start -1.1303 3.199892)
			(end 8.3693 -3.199892)
			(stroke
				(width 0)
				(type default)
			)
			(fill no)
			(layer "F.CrtYd")
		)
		(fp_line
			(start 8.3693 3.199892)
			(end -1.1303 3.199892)
			(stroke
				(width 0.1)
				(type default)
			)
			(layer "F.Fab")
		)
		(fp_line
			(start 8.3693 -3.199892)
			(end 8.3693 3.199892)
			(stroke
				(width 0.1)
				(type default)
			)
			(layer "F.Fab")
		)
		(fp_line
			(start -1.1303 3.199892)
			(end -1.1303 -3.199892)
			(stroke
				(width 0.1)
				(type default)
			)
			(layer "F.Fab")
		)
		(fp_line
			(start -1.1303 -3.199892)
			(end 8.3693 -3.199892)
			(stroke
				(width 0.1)
				(type default)
			)
			(layer "F.Fab")
		)
		(pad "1" smd rect
			(at 0 0 180)
			(size 3.683 2.667)
			(layers "F.Cu" "F.Mask" "F.Paste")
			(net "VR_PVCCIO_CPU0_PH1_SW")
		)
		(pad "2" smd rect
			(at 7.239 0 180)
			(size 3.683 2.667)
			(layers "F.Cu" "F.Mask" "F.Paste")
			(net "PVCCIO_CPU0")
		)
	)
)
